(kicad_pcb
	(version 20241229)
	(generator "pcbnew")
	(generator_version "9.0")
	(general
		(thickness 1.62)
		(legacy_teardrops no)
	)
	(paper "A4")
	(title_block
		(title "OCuLink to 10GbE adapter")
		(date "2026-02-23")
		(rev "1.1.0")
		(company "Antmicro Ltd")
		(comment 1 "www.antmicro.com")
		(comment 9 "footprints 424-428 of 510")
	)
	(layers
		(0 "F.Cu" signal)
		(4 "In1.Cu" signal)
		(6 "In2.Cu" signal)
		(8 "In3.Cu" signal)
		(10 "In4.Cu" signal)
		(12 "In5.Cu" signal)
		(14 "In6.Cu" signal)
		(2 "B.Cu" signal)
		(9 "F.Adhes" user "F.Adhesive")
		(11 "B.Adhes" user "B.Adhesive")
		(13 "F.Paste" user)
		(15 "B.Paste" user)
		(5 "F.SilkS" user "F.Silkscreen")
		(7 "B.SilkS" user "B.Silkscreen")
		(1 "F.Mask" user)
		(3 "B.Mask" user)
		(17 "Dwgs.User" user "User.Drawings")
		(19 "Cmts.User" user "User.Comments")
		(21 "Eco1.User" user "User.Eco1")
		(23 "Eco2.User" user "User.Eco2")
		(25 "Edge.Cuts" user)
		(27 "Margin" user)
		(31 "F.CrtYd" user "F.Courtyard")
		(29 "B.CrtYd" user "B.Courtyard")
		(35 "F.Fab" user)
		(33 "B.Fab" user)
	)
	(footprint "antmicro-footprints:C_0402_1005Metric"
		(layer "B.Cu")
		(at 80.47 106.93 -90)
		(descr "Capacitor SMD 0402")
		(tags "capacitor SMD 0402")
		(property "Reference" "C143"
			(at 9.97 -0.91 90)
			(layer "B.SilkS")
			(effects
				(font
					(size 0.7 0.7)
					(thickness 0.15)
				)
				(justify left bottom mirror)
			)
		)
		(property "Value" "C_1u_25V_0402"
			(at -1.022927 -2.155213 90)
			(layer "B.Fab")
			(hide yes)
			(effects
				(font
					(size 0.7 0.7)
					(thickness 0.15)
				)
				(justify left bottom mirror)
			)
		)
		(property "Datasheet" "https://www.murata.com/products/productdetail?partno=GRM155R61E105KE11%23"
			(at 0 0 90)
			(layer "B.Fab")
			(hide yes)
			(effects
				(font
					(size 1.27 1.27)
					(thickness 0.15)
				)
				(justify mirror)
			)
		)
		(property "Description" "SMD Multilayer Ceramic Capacitor, 1 µF, 25 V, 0402 [1005 Metric], ± 10%, X5R, GRM Series"
			(at 0 0 90)
			(layer "B.Fab")
			(hide yes)
			(effects
				(font
					(size 1.27 1.27)
					(thickness 0.15)
				)
				(justify mirror)
			)
		)
		(property "MPN" "GRM155R61E105KE11J"
			(at 0 0 270)
			(unlocked yes)
			(layer "B.Fab")
			(hide yes)
			(effects
				(font
					(size 1 1)
					(thickness 0.15)
				)
				(justify mirror)
			)
		)
		(property "Manufacturer" "Murata"
			(at 0 0 270)
			(unlocked yes)
			(layer "B.Fab")
			(hide yes)
			(effects
				(font
					(size 1 1)
					(thickness 0.15)
				)
				(justify mirror)
			)
		)
		(property "License" "Apache-2.0"
			(at 0 0 270)
			(unlocked yes)
			(layer "B.Fab")
			(hide yes)
			(effects
				(font
					(size 1 1)
					(thickness 0.15)
				)
				(justify mirror)
			)
		)
		(property "Author" "Antmicro"
			(at 0 0 270)
			(unlocked yes)
			(layer "B.Fab")
			(hide yes)
			(effects
				(font
					(size 1 1)
					(thickness 0.15)
				)
				(justify mirror)
			)
		)
		(property "Val" "1u"
			(at 0 0 270)
			(unlocked yes)
			(layer "B.Fab")
			(hide yes)
			(effects
				(font
					(size 1 1)
					(thickness 0.15)
				)
				(justify mirror)
			)
		)
		(property "Voltage" "25V"
			(at 0 0 270)
			(unlocked yes)
			(layer "B.Fab")
			(hide yes)
			(effects
				(font
					(size 1 1)
					(thickness 0.15)
				)
				(justify mirror)
			)
		)
		(property "Dielectric" "X5R"
			(at 0 0 270)
			(unlocked yes)
			(layer "B.Fab")
			(hide yes)
			(effects
				(font
					(size 1 1)
					(thickness 0.15)
				)
				(justify mirror)
			)
		)
		(sheetname "/X710-AT2 power/")
		(sheetfile "x710-at2-power.kicad_sch")
		(attr smd)
		(fp_rect
			(start -0.925 0.47)
			(end 0.925 -0.47)
			(stroke
				(width 0.05)
				(type default)
			)
			(fill no)
			(layer "B.CrtYd")
		)
		(fp_line
			(start -0.494 0.25)
			(end 0.504 0.25)
			(stroke
				(width 0.15)
				(type solid)
			)
			(layer "B.Fab")
		)
		(fp_line
			(start 0.504 0.25)
			(end 0.504 -0.248)
			(stroke
				(width 0.15)
				(type solid)
			)
			(layer "B.Fab")
		)
		(fp_line
			(start -0.494 -0.248)
			(end -0.494 0.25)
			(stroke
				(width 0.15)
				(type solid)
			)
			(layer "B.Fab")
		)
		(fp_line
			(start 0.504 -0.248)
			(end -0.494 -0.248)
			(stroke
				(width 0.15)
				(type solid)
			)
			(layer "B.Fab")
		)
		(pad "1" smd roundrect
			(at -0.48 0 270)
			(size 0.59 0.64)
			(layers "B.Cu" "B.Mask" "B.Paste")
			(roundrect_rratio 0.25)
			(net 28 "GND")
			(pintype "passive")
		)
		(pad "2" smd roundrect
			(at 0.48 0 270)
			(size 0.59 0.64)
			(layers "B.Cu" "B.Mask" "B.Paste")
			(roundrect_rratio 0.25)
			(net 10 "AVDDH")
			(pintype "passive")
		)
	)
	(footprint "antmicro-footprints:C_0402_1005Metric"
		(layer "B.Cu")
		(at 88 131.4)
		(descr "Capacitor SMD 0402")
		(tags "capacitor SMD 0402")
		(property "Reference" "C64"
			(at -0.98 2.59 0)
			(layer "B.SilkS")
			(effects
				(font
					(size 0.7 0.7)
					(thickness 0.15)
				)
				(justify right top mirror)
			)
		)
		(property "Value" "C_1u_25V_0402"
			(at -1.022927 -2.155213 0)
			(layer "B.Fab")
			(hide yes)
			(effects
				(font
					(size 0.7 0.7)
					(thickness 0.15)
				)
				(justify right top mirror)
			)
		)
		(property "Datasheet" "https://www.murata.com/products/productdetail?partno=GRM155R61E105KE11%23"
			(at 0 0 0)
			(layer "B.Fab")
			(hide yes)
			(effects
				(font
					(size 1.27 1.27)
					(thickness 0.15)
				)
				(justify mirror)
			)
		)
		(property "Description" "SMD Multilayer Ceramic Capacitor, 1 µF, 25 V, 0402 [1005 Metric], ± 10%, X5R, GRM Series"
			(at 0 0 0)
			(layer "B.Fab")
			(hide yes)
			(effects
				(font
					(size 1.27 1.27)
					(thickness 0.15)
				)
				(justify mirror)
			)
		)
		(property "MPN" "GRM155R61E105KE11J"
			(at 0 0 0)
			(unlocked yes)
			(layer "B.Fab")
			(hide yes)
			(effects
				(font
					(size 1 1)
					(thickness 0.15)
				)
				(justify mirror)
			)
		)
		(property "Manufacturer" "Murata"
			(at 0 0 0)
			(unlocked yes)
			(layer "B.Fab")
			(hide yes)
			(effects
				(font
					(size 1 1)
					(thickness 0.15)
				)
				(justify mirror)
			)
		)
		(property "License" "Apache-2.0"
			(at 0 0 0)
			(unlocked yes)
			(layer "B.Fab")
			(hide yes)
			(effects
				(font
					(size 1 1)
					(thickness 0.15)
				)
				(justify mirror)
			)
		)
		(property "Author" "Antmicro"
			(at 0 0 0)
			(unlocked yes)
			(layer "B.Fab")
			(hide yes)
			(effects
				(font
					(size 1 1)
					(thickness 0.15)
				)
				(justify mirror)
			)
		)
		(property "Val" "1u"
			(at 0 0 0)
			(unlocked yes)
			(layer "B.Fab")
			(hide yes)
			(effects
				(font
					(size 1 1)
					(thickness 0.15)
				)
				(justify mirror)
			)
		)
		(property "Voltage" "25V"
			(at 0 0 0)
			(unlocked yes)
			(layer "B.Fab")
			(hide yes)
			(effects
				(font
					(size 1 1)
					(thickness 0.15)
				)
				(justify mirror)
			)
		)
		(property "Dielectric" "X5R"
			(at 0 0 0)
			(unlocked yes)
			(layer "B.Fab")
			(hide yes)
			(effects
				(font
					(size 1 1)
					(thickness 0.15)
				)
				(justify mirror)
			)
		)
		(sheetname "/2xRJ45/")
		(sheetfile "2xrj45.kicad_sch")
		(attr smd)
		(fp_rect
			(start -0.925 0.47)
			(end 0.925 -0.47)
			(stroke
				(width 0.05)
				(type default)
			)
			(fill no)
			(layer "B.CrtYd")
		)
		(fp_line
			(start -0.494 -0.248)
			(end -0.494 0.25)
			(stroke
				(width 0.15)
				(type solid)
			)
			(layer "B.Fab")
		)
		(fp_line
			(start -0.494 0.25)
			(end 0.504 0.25)
			(stroke
				(width 0.15)
				(type solid)
			)
			(layer "B.Fab")
		)
		(fp_line
			(start 0.504 -0.248)
			(end -0.494 -0.248)
			(stroke
				(width 0.15)
				(type solid)
			)
			(layer "B.Fab")
		)
		(fp_line
			(start 0.504 0.25)
			(end 0.504 -0.248)
			(stroke
				(width 0.15)
				(type solid)
			)
			(layer "B.Fab")
		)
		(pad "1" smd roundrect
			(at -0.48 0)
			(size 0.59 0.64)
			(layers "B.Cu" "B.Mask" "B.Paste")
			(roundrect_rratio 0.25)
			(net 28 "GND")
			(pintype "passive")
		)
		(pad "2" smd roundrect
			(at 0.48 0)
			(size 0.59 0.64)
			(layers "B.Cu" "B.Mask" "B.Paste")
			(roundrect_rratio 0.25)
			(net 300 "/2xRJ45/P1_CT")
			(pintype "passive")
		)
	)
	(footprint "antmicro-footprints:R_0402_1005Metric"
		(layer "B.Cu")
		(at 111.49 86.76 90)
		(descr "Resistor SMD 0402")
		(tags "resistor SMD 0402")
		(property "Reference" "R129"
			(at 0.81 -0.31 90)
			(layer "B.SilkS")
			(effects
				(font
					(size 0.7 0.7)
					(thickness 0.15)
				)
				(justify right top mirror)
			)
		)
		(property "Value" "R_1k_0402"
			(at -1.011843 -1.772046 90)
			(layer "B.Fab")
			(hide yes)
			(effects
				(font
					(size 0.7 0.7)
					(thickness 0.15)
				)
				(justify right top mirror)
			)
		)
		(property "Datasheet" "https://www.bourns.com/docs/product-datasheets/cr.pdf"
			(at 0 0 90)
			(layer "B.Fab")
			(hide yes)
			(effects
				(font
					(size 1.27 1.27)
					(thickness 0.15)
				)
				(justify mirror)
			)
		)
		(property "Description" "SMD Chip Resistor, 1 kohm, ± 1%, 63 mW, 0402 [1005 Metric], Thick Film, General Purpose"
			(at 0 0 90)
			(layer "B.Fab")
			(hide yes)
			(effects
				(font
					(size 1.27 1.27)
					(thickness 0.15)
				)
				(justify mirror)
			)
		)
		(property "MPN" "CR0402-FX-1001GLF"
			(at 0 0 90)
			(unlocked yes)
			(layer "B.Fab")
			(hide yes)
			(effects
				(font
					(size 1 1)
					(thickness 0.15)
				)
				(justify mirror)
			)
		)
		(property "Manufacturer" "Bourns"
			(at 0 0 90)
			(unlocked yes)
			(layer "B.Fab")
			(hide yes)
			(effects
				(font
					(size 1 1)
					(thickness 0.15)
				)
				(justify mirror)
			)
		)
		(property "License" "Apache-2.0"
			(at 0 0 90)
			(unlocked yes)
			(layer "B.Fab")
			(hide yes)
			(effects
				(font
					(size 1 1)
					(thickness 0.15)
				)
				(justify mirror)
			)
		)
		(property "Author" "Antmicro"
			(at 0 0 90)
			(unlocked yes)
			(layer "B.Fab")
			(hide yes)
			(effects
				(font
					(size 1 1)
					(thickness 0.15)
				)
				(justify mirror)
			)
		)
		(property "Val" "1k"
			(at 0 0 90)
			(unlocked yes)
			(layer "B.Fab")
			(hide yes)
			(effects
				(font
					(size 1 1)
					(thickness 0.15)
				)
				(justify mirror)
			)
		)
		(property "Tolerance" "1%"
			(at 0 0 90)
			(unlocked yes)
			(layer "B.Fab")
			(hide yes)
			(effects
				(font
					(size 1 1)
					(thickness 0.15)
				)
				(justify mirror)
			)
		)
		(sheetname "/X710-AT2 RSVD/")
		(sheetfile "x710-at2-rsvd.kicad_sch")
		(attr smd)
		(fp_rect
			(start -0.925 0.47)
			(end 0.925 -0.47)
			(stroke
				(width 0.05)
				(type default)
			)
			(fill no)
			(layer "B.CrtYd")
		)
		(fp_rect
			(start -0.5 0.25)
			(end 0.5 -0.25)
			(stroke
				(width 0.15)
				(type solid)
			)
			(fill no)
			(layer "B.Fab")
		)
		(pad "1" smd roundrect
			(at -0.48 0 90)
			(size 0.59 0.64)
			(layers "B.Cu" "B.Mask" "B.Paste")
			(roundrect_rratio 0.25)
			(net 120 "/X710-AT2 RSVD/DEBUG_W7")
			(pintype "passive")
		)
		(pad "2" smd roundrect
			(at 0.48 0 90)
			(size 0.59 0.64)
			(layers "B.Cu" "B.Mask" "B.Paste")
			(roundrect_rratio 0.25)
			(net 114 "/X710-AT2 RSVD/DEBUG_EN")
			(pintype "passive")
		)
	)
	(footprint "antmicro-footprints:R_0402_1005Metric"
		(layer "B.Cu")
		(at 109.5 71.6 180)
		(descr "Resistor SMD 0402")
		(tags "resistor SMD 0402")
		(property "Reference" "R169"
			(at -1.44 5.61 0)
			(layer "B.SilkS")
			(effects
				(font
					(size 0.7 0.7)
					(thickness 0.15)
				)
				(justify left bottom mirror)
			)
		)
		(property "Value" "R_0R_0402"
			(at -1.011843 -1.772046 0)
			(layer "B.Fab")
			(hide yes)
			(effects
				(font
					(size 0.7 0.7)
					(thickness 0.15)
				)
				(justify left bottom mirror)
			)
		)
		(property "Datasheet" "https://industrial.panasonic.com/cdbs/www-data/pdf/RDA0000/AOA0000C301.pdf"
			(at 0 0 0)
			(layer "B.Fab")
			(hide yes)
			(effects
				(font
					(size 1.27 1.27)
					(thickness 0.15)
				)
				(justify mirror)
			)
		)
		(property "Description" "SMD Chip Resistor, Jumper, 0 ohm, 100 mW, 0402 [1005 Metric], Thick Film, General Purpose"
			(at 0 0 0)
			(layer "B.Fab")
			(hide yes)
			(effects
				(font
					(size 1.27 1.27)
					(thickness 0.15)
				)
				(justify mirror)
			)
		)
		(property "MPN" "ERJ2GE0R00X"
			(at 0 0 180)
			(unlocked yes)
			(layer "B.Fab")
			(hide yes)
			(effects
				(font
					(size 1 1)
					(thickness 0.15)
				)
				(justify mirror)
			)
		)
		(property "Manufacturer" "Panasonic"
			(at 0 0 180)
			(unlocked yes)
			(layer "B.Fab")
			(hide yes)
			(effects
				(font
					(size 1 1)
					(thickness 0.15)
				)
				(justify mirror)
			)
		)
		(property "License" "Apache-2.0"
			(at 0 0 180)
			(unlocked yes)
			(layer "B.Fab")
			(hide yes)
			(effects
				(font
					(size 1 1)
					(thickness 0.15)
				)
				(justify mirror)
			)
		)
		(property "Author" "Antmicro"
			(at 0 0 180)
			(unlocked yes)
			(layer "B.Fab")
			(hide yes)
			(effects
				(font
					(size 1 1)
					(thickness 0.15)
				)
				(justify mirror)
			)
		)
		(property "Val" "0R"
			(at 0 0 180)
			(unlocked yes)
			(layer "B.Fab")
			(hide yes)
			(effects
				(font
					(size 1 1)
					(thickness 0.15)
				)
				(justify mirror)
			)
		)
		(property "Tolerance" "~"
			(at 0 0 180)
			(unlocked yes)
			(layer "B.Fab")
			(hide yes)
			(effects
				(font
					(size 1 1)
					(thickness 0.15)
				)
				(justify mirror)
			)
		)
		(property "Current" "1A"
			(at 0 0 180)
			(unlocked yes)
			(layer "B.Fab")
			(hide yes)
			(effects
				(font
					(size 1 1)
					(thickness 0.15)
				)
				(justify mirror)
			)
		)
		(sheetname "/OCuLink/")
		(sheetfile "oculink.kicad_sch")
		(attr smd)
		(fp_rect
			(start -0.925 0.47)
			(end 0.925 -0.47)
			(stroke
				(width 0.05)
				(type default)
			)
			(fill no)
			(layer "B.CrtYd")
		)
		(fp_rect
			(start -0.5 0.25)
			(end 0.5 -0.25)
			(stroke
				(width 0.15)
				(type solid)
			)
			(fill no)
			(layer "B.Fab")
		)
		(pad "1" smd roundrect
			(at -0.48 0 180)
			(size 0.59 0.64)
			(layers "B.Cu" "B.Mask" "B.Paste")
			(roundrect_rratio 0.25)
			(net 320 "/OCuLink/~{CWAKE}_R")
			(pintype "passive")
		)
		(pad "2" smd roundrect
			(at 0.48 0 180)
			(size 0.59 0.64)
			(layers "B.Cu" "B.Mask" "B.Paste")
			(roundrect_rratio 0.25)
			(net 309 "/OCuLink/~{PE_WAKE}")
			(pintype "passive")
		)
	)
	(footprint "antmicro-footprints:C_0402_1005Metric"
		(layer "B.Cu")
		(at 84.375 107.895 -90)
		(descr "Capacitor SMD 0402")
		(tags "capacitor SMD 0402")
		(property "Reference" "C177"
			(at 0.805 -0.355 90)
			(layer "B.SilkS")
			(effects
				(font
					(size 0.7 0.7)
					(thickness 0.15)
				)
				(justify left bottom mirror)
			)
		)
		(property "Value" "C_1u_25V_0402"
			(at -1.022927 -2.155213 90)
			(layer "B.Fab")
			(hide yes)
			(effects
				(font
					(size 0.7 0.7)
					(thickness 0.15)
				)
				(justify left bottom mirror)
			)
		)
		(property "Datasheet" "https://www.murata.com/products/productdetail?partno=GRM155R61E105KE11%23"
			(at 0 0 90)
			(layer "B.Fab")
			(hide yes)
			(effects
				(font
					(size 1.27 1.27)
					(thickness 0.15)
				)
				(justify mirror)
			)
		)
		(property "Description" "SMD Multilayer Ceramic Capacitor, 1 µF, 25 V, 0402 [1005 Metric], ± 10%, X5R, GRM Series"
			(at 0 0 90)
			(layer "B.Fab")
			(hide yes)
			(effects
				(font
					(size 1.27 1.27)
					(thickness 0.15)
				)
				(justify mirror)
			)
		)
		(property "MPN" "GRM155R61E105KE11J"
			(at 0 0 270)
			(unlocked yes)
			(layer "B.Fab")
			(hide yes)
			(effects
				(font
					(size 1 1)
					(thickness 0.15)
				)
				(justify mirror)
			)
		)
		(property "Manufacturer" "Murata"
			(at 0 0 270)
			(unlocked yes)
			(layer "B.Fab")
			(hide yes)
			(effects
				(font
					(size 1 1)
					(thickness 0.15)
				)
				(justify mirror)
			)
		)
		(property "License" "Apache-2.0"
			(at 0 0 270)
			(unlocked yes)
			(layer "B.Fab")
			(hide yes)
			(effects
				(font
					(size 1 1)
					(thickness 0.15)
				)
				(justify mirror)
			)
		)
		(property "Author" "Antmicro"
			(at 0 0 270)
			(unlocked yes)
			(layer "B.Fab")
			(hide yes)
			(effects
				(font
					(size 1 1)
					(thickness 0.15)
				)
				(justify mirror)
			)
		)
		(property "Val" "1u"
			(at 0 0 270)
			(unlocked yes)
			(layer "B.Fab")
			(hide yes)
			(effects
				(font
					(size 1 1)
					(thickness 0.15)
				)
				(justify mirror)
			)
		)
		(property "Voltage" "25V"
			(at 0 0 270)
			(unlocked yes)
			(layer "B.Fab")
			(hide yes)
			(effects
				(font
					(size 1 1)
					(thickness 0.15)
				)
				(justify mirror)
			)
		)
		(property "Dielectric" "X5R"
			(at 0 0 270)
			(unlocked yes)
			(layer "B.Fab")
			(hide yes)
			(effects
				(font
					(size 1 1)
					(thickness 0.15)
				)
				(justify mirror)
			)
		)
		(sheetname "/X710-AT2 power/")
		(sheetfile "x710-at2-power.kicad_sch")
		(attr smd)
		(fp_rect
			(start -0.925 0.47)
			(end 0.925 -0.47)
			(stroke
				(width 0.05)
				(type default)
			)
			(fill no)
			(layer "B.CrtYd")
		)
		(fp_line
			(start -0.494 0.25)
			(end 0.504 0.25)
			(stroke
				(width 0.15)
				(type solid)
			)
			(layer "B.Fab")
		)
		(fp_line
			(start 0.504 0.25)
			(end 0.504 -0.248)
			(stroke
				(width 0.15)
				(type solid)
			)
			(layer "B.Fab")
		)
		(fp_line
			(start -0.494 -0.248)
			(end -0.494 0.25)
			(stroke
				(width 0.15)
				(type solid)
			)
			(layer "B.Fab")
		)
		(fp_line
			(start 0.504 -0.248)
			(end -0.494 -0.248)
			(stroke
				(width 0.15)
				(type solid)
			)
			(layer "B.Fab")
		)
		(pad "1" smd roundrect
			(at -0.48 0 270)
			(size 0.59 0.64)
			(layers "B.Cu" "B.Mask" "B.Paste")
			(roundrect_rratio 0.25)
			(net 28 "GND")
			(pintype "passive")
		)
		(pad "2" smd roundrect
			(at 0.48 0 270)
			(size 0.59 0.64)
			(layers "B.Cu" "B.Mask" "B.Paste")
			(roundrect_rratio 0.25)
			(net 14 "P1_AVDDL")
			(pintype "passive")
		)
	)
)
